# T6G (Grand Teton) — schematic netlist excerpt (pin names and nets, part order shuffled) for the footprints in the layout excerpt that follows; sources: Cadence DE-HDL packaged netlist, KiCad conversion of 04192023_DAF0TMB3IC0_F0TG_MB_C_brd_V02_OCP.brd

C2479  Q_CAP  22UF 4V 20% X6S  pkg C0402  page 74 : A = PVDDIO_P1 ; B = GND
PR410  Q_RES  1K 1% CHIP  pkg 0402LF  page 205 : A = PVDDIO_P0 ; B = GND

(kicad_pcb
	(version 20260206)
	(generator "pcbnew")
	(generator_version "10.0")
	(general
		(thickness 1.6)
		(legacy_teardrops no)
	)
	(paper "A4")
	(title_block
		(title "04192023_DAF0TMB3IC0_F0TG_MB_C_brd_V02_OCP.brd")
		(comment 1 "Grand Teton / footprints 6140-6141 of 8354")
	)
	(layers
		(0 "F.Cu" signal "TOP")
		(4 "In1.Cu" signal "GND")
		(6 "In2.Cu" signal "IN1")
		(8 "In3.Cu" signal "GND1")
		(10 "In4.Cu" signal "IN2")
		(12 "In5.Cu" signal "GND2")
		(14 "In6.Cu" signal "IN3")
		(16 "In7.Cu" signal "GND3")
		(18 "In8.Cu" signal "VCC")
		(20 "In9.Cu" signal "VCC1")
		(22 "In10.Cu" signal "GND4")
		(24 "In11.Cu" signal "IN4")
		(26 "In12.Cu" signal "GND5")
		(28 "In13.Cu" signal "IN5")
		(30 "In14.Cu" signal "GND6")
		(32 "In15.Cu" signal "IN6")
		(34 "In16.Cu" signal "GND7")
		(2 "B.Cu" signal "BOTTOM")
		(9 "F.Adhes" user "F.Adhesive")
		(11 "B.Adhes" user "B.Adhesive")
		(13 "F.Paste" user "Package Geometry/Pastemask Top")
		(15 "B.Paste" user "Package Geometry/Pastemask Bottom")
		(5 "F.SilkS" user "Ref Des/Silkscreen Top")
		(7 "B.SilkS" user "Ref Des/Silkscreen Bottom")
		(1 "F.Mask" user "Board Geometry/Soldermask Top")
		(3 "B.Mask" user "Board Geometry/Soldermask Bottom")
		(17 "Dwgs.User" user "User.Drawings")
		(19 "Cmts.User" user "User.Comments")
		(21 "Eco1.User" user "User.Eco1")
		(23 "Eco2.User" user "User.Eco2")
		(25 "Edge.Cuts" user "Board Geometry/Outline")
		(27 "Margin" user)
		(31 "F.CrtYd" user "Package Geometry/Place Bound Top")
		(29 "B.CrtYd" user "Package Geometry/Place Bound Bottom")
		(35 "F.Fab" user "Ref Des/Assembly Top")
		(33 "B.Fab" user "Ref Des/Assembly Bottom")
	)
	(footprint ""
		(layer "B.Cu")
		(at 270.247872 -338.127086 -90)
		(property "Reference" "PR410"
			(at 0 0 90)
			(layer "B.SilkS")
			(hide yes)
			(effects
				(font
					(size 1.27 1.27)
				)
				(justify mirror)
			)
		)
		(property "Value" ""
			(at 0 0 90)
			(layer "B.Fab")
			(effects
				(font
					(size 1.27 1.27)
				)
				(justify mirror)
			)
		)
		(duplicate_pad_numbers_are_jumpers no)
		(fp_line
			(start -0.7874 0.4064)
			(end 0.7874 0.4064)
			(stroke
				(width 0.1524)
				(type default)
			)
			(layer "B.SilkS")
		)
		(fp_line
			(start 0.7874 0.4064)
			(end 0.7874 -0.4064)
			(stroke
				(width 0.1524)
				(type default)
			)
			(layer "B.SilkS")
		)
		(fp_line
			(start -0.7874 -0.4064)
			(end -0.7874 0.4064)
			(stroke
				(width 0.1524)
				(type default)
			)
			(layer "B.SilkS")
		)
		(fp_line
			(start 0.7874 -0.4064)
			(end -0.7874 -0.4064)
			(stroke
				(width 0.1524)
				(type default)
			)
			(layer "B.SilkS")
		)
		(fp_line
			(start -0.67945 0.3048)
			(end -0.120396 0.3048)
			(stroke
				(width 0.1)
				(type default)
			)
			(layer "B.Fab")
		)
		(fp_line
			(start -0.120396 0.3048)
			(end -0.120396 0.2794)
			(stroke
				(width 0.1)
				(type default)
			)
			(layer "B.Fab")
		)
		(fp_line
			(start 0.12065 0.3048)
			(end 0.67945 0.3048)
			(stroke
				(width 0.1)
				(type default)
			)
			(layer "B.Fab")
		)
		(fp_line
			(start 0.67945 0.3048)
			(end 0.67945 -0.305054)
			(stroke
				(width 0.1)
				(type default)
			)
			(layer "B.Fab")
		)
		(fp_line
			(start -0.120396 0.2794)
			(end 0.12065 0.2794)
			(stroke
				(width 0.1)
				(type default)
			)
			(layer "B.Fab")
		)
		(fp_line
			(start 0.12065 0.2794)
			(end 0.12065 0.3048)
			(stroke
				(width 0.1)
				(type default)
			)
			(layer "B.Fab")
		)
		(fp_line
			(start -0.12065 -0.2794)
			(end -0.12065 -0.3048)
			(stroke
				(width 0.1)
				(type default)
			)
			(layer "B.Fab")
		)
		(fp_line
			(start 0.12065 -0.2794)
			(end -0.12065 -0.2794)
			(stroke
				(width 0.1)
				(type default)
			)
			(layer "B.Fab")
		)
		(fp_line
			(start -0.67945 -0.3048)
			(end -0.67945 0.3048)
			(stroke
				(width 0.1)
				(type default)
			)
			(layer "B.Fab")
		)
		(fp_line
			(start -0.12065 -0.3048)
			(end -0.67945 -0.3048)
			(stroke
				(width 0.1)
				(type default)
			)
			(layer "B.Fab")
		)
		(fp_line
			(start 0.12065 -0.305054)
			(end 0.12065 -0.2794)
			(stroke
				(width 0.1)
				(type default)
			)
			(layer "B.Fab")
		)
		(fp_line
			(start 0.67945 -0.305054)
			(end 0.12065 -0.305054)
			(stroke
				(width 0.1)
				(type default)
			)
			(layer "B.Fab")
		)
		(pad "1" smd circle
			(at 0.40005 0 90)
			(size 0 0)
			(layers "B.Cu" "B.Mask" "B.Paste")
			(net "PVDDIO_P0")
		)
		(pad "2" smd circle
			(at -0.40005 0 90)
			(size 0 0)
			(layers "B.Cu" "B.Mask" "B.Paste")
			(net "GND")
		)
	)
	(footprint ""
		(layer "B.Cu")
		(at 105.960164 -258.405376 180)
		(property "Reference" "C2479"
			(at 0 0 0)
			(layer "B.SilkS")
			(hide yes)
			(effects
				(font
					(size 1.27 1.27)
				)
				(justify mirror)
			)
		)
		(property "Value" ""
			(at 0 0 0)
			(layer "B.Fab")
			(effects
				(font
					(size 1.27 1.27)
				)
				(justify mirror)
			)
		)
		(duplicate_pad_numbers_are_jumpers no)
		(fp_line
			(start 0.7874 0.4064)
			(end 0.7874 -0.4064)
			(stroke
				(width 0.1524)
				(type default)
			)
			(layer "B.SilkS")
		)
		(fp_line
			(start 0.7874 -0.4064)
			(end -0.7874 -0.4064)
			(stroke
				(width 0.1524)
				(type default)
			)
			(layer "B.SilkS")
		)
		(fp_line
			(start -0.7874 0.4064)
			(end 0.7874 0.4064)
			(stroke
				(width 0.1524)
				(type default)
			)
			(layer "B.SilkS")
		)
		(fp_line
			(start -0.7874 -0.4064)
			(end -0.7874 0.4064)
			(stroke
				(width 0.1524)
				(type default)
			)
			(layer "B.SilkS")
		)
		(fp_line
			(start 0.67945 0.3048)
			(end 0.67945 -0.305054)
			(stroke
				(width 0.1)
				(type default)
			)
			(layer "B.Fab")
		)
		(fp_line
			(start 0.67945 -0.305054)
			(end 0.12065 -0.305054)
			(stroke
				(width 0.1)
				(type default)
			)
			(layer "B.Fab")
		)
		(fp_line
			(start 0.12065 0.3048)
			(end 0.67945 0.3048)
			(stroke
				(width 0.1)
				(type default)
			)
			(layer "B.Fab")
		)
		(fp_line
			(start 0.12065 0.2794)
			(end 0.12065 0.3048)
			(stroke
				(width 0.1)
				(type default)
			)
			(layer "B.Fab")
		)
		(fp_line
			(start 0.12065 -0.2794)
			(end -0.12065 -0.2794)
			(stroke
				(width 0.1)
				(type default)
			)
			(layer "B.Fab")
		)
		(fp_line
			(start 0.12065 -0.305054)
			(end 0.12065 -0.2794)
			(stroke
				(width 0.1)
				(type default)
			)
			(layer "B.Fab")
		)
		(fp_line
			(start -0.120396 0.3048)
			(end -0.120396 0.2794)
			(stroke
				(width 0.1)
				(type default)
			)
			(layer "B.Fab")
		)
		(fp_line
			(start -0.120396 0.2794)
			(end 0.12065 0.2794)
			(stroke
				(width 0.1)
				(type default)
			)
			(layer "B.Fab")
		)
		(fp_line
			(start -0.12065 -0.2794)
			(end -0.12065 -0.3048)
			(stroke
				(width 0.1)
				(type default)
			)
			(layer "B.Fab")
		)
		(fp_line
			(start -0.12065 -0.3048)
			(end -0.67945 -0.3048)
			(stroke
				(width 0.1)
				(type default)
			)
			(layer "B.Fab")
		)
		(fp_line
			(start -0.67945 0.3048)
			(end -0.120396 0.3048)
			(stroke
				(width 0.1)
				(type default)
			)
			(layer "B.Fab")
		)
		(fp_line
			(start -0.67945 -0.3048)
			(end -0.67945 0.3048)
			(stroke
				(width 0.1)
				(type default)
			)
			(layer "B.Fab")
		)
		(pad "1" smd circle
			(at 0.40005 0)
			(size 0 0)
			(layers "B.Cu" "B.Mask" "B.Paste")
			(net "PVDDIO_P1")
		)
		(pad "2" smd circle
			(at -0.40005 0)
			(size 0 0)
			(layers "B.Cu" "B.Mask" "B.Paste")
			(net "GND")
		)
	)
)
